# BASEBOARD_FAB2 (Tioga Pass) — schematic netlist excerpt (pin names and nets, part order shuffled) for the footprints in the layout excerpt that follows; sources: Cadence DE-HDL packaged netlist, KiCad conversion of Wiwynn_Tioga_Pass_MB.brd

C4D46  CAP  1.0UF 16V 10% X6S  pkg 0402  page 204 : A = VR_PVCCIN_CPU0_PH5_VCIN ; B = GND
C3W4  CAP_A  22.0UF 4V 20% X6S  pkg 0603V  page 76 : A = PVCCMCP_CPU1 ; B = GND
C827  CAP  0.22UF 16V 10% X7R  pkg 0402  page 244 : A = P3E_CPU0_PE1_PCH_TXP<14> ; B = P3E_CPU0_PE1_PCH_CON_TXP<14>

(kicad_pcb
	(version 20260206)
	(generator "pcbnew")
	(generator_version "10.0")
	(general
		(thickness 1.6)
		(legacy_teardrops no)
	)
	(paper "A4")
	(title_block
		(title "Wiwynn_Tioga_Pass_MB.brd")
		(comment 1 "Tioga Pass / footprints 840-842 of 4770")
	)
	(layers
		(0 "F.Cu" signal "TOP")
		(4 "In1.Cu" signal "L2GND")
		(6 "In2.Cu" signal "L3")
		(8 "In3.Cu" signal "L4GND")
		(10 "In4.Cu" signal "L5")
		(12 "In5.Cu" signal "L6GND")
		(14 "In6.Cu" signal "L7VCC")
		(16 "In7.Cu" signal "L8VCC")
		(18 "In8.Cu" signal "L9GND")
		(20 "In9.Cu" signal "L10")
		(22 "In10.Cu" signal "L11GND")
		(24 "In11.Cu" signal "L12")
		(26 "In12.Cu" signal "L13GND")
		(2 "B.Cu" signal "BOTTOM")
		(9 "F.Adhes" user "F.Adhesive")
		(11 "B.Adhes" user "B.Adhesive")
		(13 "F.Paste" user "Package Geometry/Pastemask Top")
		(15 "B.Paste" user "Package Geometry/Pastemask Bottom")
		(5 "F.SilkS" user "Ref Des/Silkscreen Top")
		(7 "B.SilkS" user "Ref Des/Silkscreen Bottom")
		(1 "F.Mask" user "Board Geometry/Soldermask Top")
		(3 "B.Mask" user "Board Geometry/Soldermask Bottom")
		(17 "Dwgs.User" user "User.Drawings")
		(19 "Cmts.User" user "User.Comments")
		(21 "Eco1.User" user "User.Eco1")
		(23 "Eco2.User" user "User.Eco2")
		(25 "Edge.Cuts" user "Board Geometry/Outline")
		(27 "Margin" user)
		(31 "F.CrtYd" user "Package Geometry/Place Bound Top")
		(29 "B.CrtYd" user "Package Geometry/Place Bound Bottom")
		(35 "F.Fab" user "Ref Des/Assembly Top")
		(33 "B.Fab" user "Ref Des/Assembly Bottom")
	)
	(footprint ""
		(layer "F.Cu")
		(at 324.5485 -122.555 -90)
		(property "Reference" "C827"
			(at -0.8382 -0.67818 270)
			(unlocked yes)
			(layer "F.SilkS")
			(effects
				(font
					(size 0.4064 0.254)
					(thickness 0.1524)
				)
				(justify left)
			)
		)
		(property "Value" ""
			(at 0 0 270)
			(layer "F.Fab")
			(effects
				(font
					(size 1.27 1.27)
				)
			)
		)
		(duplicate_pad_numbers_are_jumpers no)
		(fp_poly
			(pts
				(xy 0.3048 -0.1016) (xy 0.3048 0.9906) (xy -0.3048 0.9906) (xy -0.3048 -0.1016)
			)
			(stroke
				(width 0)
				(type default)
			)
			(fill no)
			(layer "F.CrtYd")
		)
		(fp_line
			(start -0.3048 0.9906)
			(end 0.3048 0.9906)
			(stroke
				(width 0.1)
				(type default)
			)
			(layer "F.Fab")
		)
		(fp_line
			(start 0.3048 0.9906)
			(end 0.3048 -0.1016)
			(stroke
				(width 0.1)
				(type default)
			)
			(layer "F.Fab")
		)
		(fp_line
			(start -0.3048 -0.1016)
			(end -0.3048 0.9906)
			(stroke
				(width 0.1)
				(type default)
			)
			(layer "F.Fab")
		)
		(fp_line
			(start 0.3048 -0.1016)
			(end -0.3048 -0.1016)
			(stroke
				(width 0.1)
				(type default)
			)
			(layer "F.Fab")
		)
		(pad "1" smd rect
			(at 0 0 270)
			(size 0.508 0.508)
			(layers "F.Cu" "F.Mask" "F.Paste")
			(net "P3E_CPU0_PE1_PCH_TXP<14>")
		)
		(pad "2" smd rect
			(at 0 0.889 270)
			(size 0.508 0.508)
			(layers "F.Cu" "F.Mask" "F.Paste")
			(net "P3E_CPU0_PE1_PCH_CON_TXP<14>")
		)
		(zone
			(layer "F.Cu")
			(hatch none 0.5)
			(connect_pads
				(clearance 0)
			)
			(min_thickness 0.25)
			(keepout
				(tracks not_allowed)
				(vias allowed)
				(pads allowed)
				(copperpour not_allowed)
				(footprints allowed)
			)
			(placement
				(enabled no)
				(sheetname "")
			)
			(fill
				(thermal_gap 0.5)
				(thermal_bridge_width 0.5)
				(island_removal_mode 0)
			)
			(polygon
				(pts
					(xy 323.9135 -122.809) (xy 323.9135 -122.301) (xy 324.2945 -122.301) (xy 324.2945 -122.809)
				)
			)
		)
		(zone
			(layer "F.Cu")
			(hatch none 0.5)
			(connect_pads
				(clearance 0)
			)
			(min_thickness 0.25)
			(keepout
				(tracks allowed)
				(vias not_allowed)
				(pads allowed)
				(copperpour not_allowed)
				(footprints allowed)
			)
			(placement
				(enabled no)
				(sheetname "")
			)
			(fill
				(thermal_gap 0.5)
				(thermal_bridge_width 0.5)
				(island_removal_mode 0)
			)
			(polygon
				(pts
					(xy 324.2945 -122.809) (xy 324.2945 -122.301) (xy 323.9135 -122.301) (xy 323.9135 -122.809)
				)
			)
		)
	)
	(footprint ""
		(layer "F.Cu")
		(at 197.162928 -85.733382 -90)
		(property "Reference" "C4D46"
			(at 0 0 270)
			(layer "F.SilkS")
			(hide yes)
			(effects
				(font
					(size 1.27 1.27)
				)
			)
		)
		(property "Value" ""
			(at 0 0 270)
			(layer "F.Fab")
			(effects
				(font
					(size 1.27 1.27)
				)
			)
		)
		(duplicate_pad_numbers_are_jumpers no)
		(fp_poly
			(pts
				(xy 0.3048 -0.1016) (xy 0.3048 0.9906) (xy -0.3048 0.9906) (xy -0.3048 -0.1016)
			)
			(stroke
				(width 0)
				(type default)
			)
			(fill no)
			(layer "F.CrtYd")
		)
		(fp_line
			(start -0.3048 0.9906)
			(end 0.3048 0.9906)
			(stroke
				(width 0.1)
				(type default)
			)
			(layer "F.Fab")
		)
		(fp_line
			(start 0.3048 0.9906)
			(end 0.3048 -0.1016)
			(stroke
				(width 0.1)
				(type default)
			)
			(layer "F.Fab")
		)
		(fp_line
			(start -0.3048 -0.1016)
			(end -0.3048 0.9906)
			(stroke
				(width 0.1)
				(type default)
			)
			(layer "F.Fab")
		)
		(fp_line
			(start 0.3048 -0.1016)
			(end -0.3048 -0.1016)
			(stroke
				(width 0.1)
				(type default)
			)
			(layer "F.Fab")
		)
		(pad "1" smd rect
			(at 0 0 270)
			(size 0.508 0.508)
			(layers "F.Cu" "F.Mask" "F.Paste")
			(net "VR_PVCCIN_CPU0_PH5_VCIN")
		)
		(pad "2" smd rect
			(at 0 0.889 270)
			(size 0.508 0.508)
			(layers "F.Cu" "F.Mask" "F.Paste")
			(net "GND")
		)
		(zone
			(layer "F.Cu")
			(hatch none 0.5)
			(connect_pads
				(clearance 0)
			)
			(min_thickness 0.25)
			(keepout
				(tracks not_allowed)
				(vias allowed)
				(pads allowed)
				(copperpour not_allowed)
				(footprints allowed)
			)
			(placement
				(enabled no)
				(sheetname "")
			)
			(fill
				(thermal_gap 0.5)
				(thermal_bridge_width 0.5)
				(island_removal_mode 0)
			)
			(polygon
				(pts
					(xy 196.527928 -85.987382) (xy 196.527928 -85.479382) (xy 196.908928 -85.479382) (xy 196.908928 -85.987382)
				)
			)
		)
		(zone
			(layer "F.Cu")
			(hatch none 0.5)
			(connect_pads
				(clearance 0)
			)
			(min_thickness 0.25)
			(keepout
				(tracks allowed)
				(vias not_allowed)
				(pads allowed)
				(copperpour not_allowed)
				(footprints allowed)
			)
			(placement
				(enabled no)
				(sheetname "")
			)
			(fill
				(thermal_gap 0.5)
				(thermal_bridge_width 0.5)
				(island_removal_mode 0)
			)
			(polygon
				(pts
					(xy 196.908928 -85.987382) (xy 196.908928 -85.479382) (xy 196.527928 -85.479382) (xy 196.527928 -85.987382)
				)
			)
		)
	)
	(footprint ""
		(layer "F.Cu")
		(at 106.982768 -79.6036 180)
		(property "Reference" "C3W4"
			(at 0.97536 0.76708 90)
			(unlocked yes)
			(layer "F.SilkS")
			(effects
				(font
					(size 0.4064 0.254)
					(thickness 0.1524)
				)
			)
		)
		(property "Value" ""
			(at 0 0 180)
			(layer "F.Fab")
			(effects
				(font
					(size 1.27 1.27)
				)
			)
		)
		(duplicate_pad_numbers_are_jumpers no)
		(fp_poly
			(pts
				(xy -0.4953 -0.2032) (xy 0.4953 -0.2032) (xy 0.4953 1.6002) (xy -0.4953 1.6002)
			)
			(stroke
				(width 0)
				(type default)
			)
			(fill no)
			(layer "F.CrtYd")
		)
		(fp_line
			(start 0.4953 1.6002)
			(end -0.4953 1.6002)
			(stroke
				(width 0.1)
				(type default)
			)
			(layer "F.Fab")
		)
		(fp_line
			(start 0.4953 -0.2032)
			(end 0.4953 1.6002)
			(stroke
				(width 0.1)
				(type default)
			)
			(layer "F.Fab")
		)
		(fp_line
			(start -0.4953 1.6002)
			(end -0.4953 -0.2032)
			(stroke
				(width 0.1)
				(type default)
			)
			(layer "F.Fab")
		)
		(fp_line
			(start -0.4953 -0.2032)
			(end 0.4953 -0.2032)
			(stroke
				(width 0.1)
				(type default)
			)
			(layer "F.Fab")
		)
		(pad "1" smd rect
			(at 0 0 180)
			(size 0.762 0.889)
			(layers "F.Cu" "F.Mask" "F.Paste")
			(net "PVCCMCP_CPU1")
		)
		(pad "2" smd rect
			(at 0 1.397 180)
			(size 0.762 0.889)
			(layers "F.Cu" "F.Mask" "F.Paste")
			(net "GND")
		)
		(zone
			(layer "F.Cu")
			(hatch none 0.5)
			(connect_pads
				(clearance 0)
			)
			(min_thickness 0.25)
			(keepout
				(tracks not_allowed)
				(vias allowed)
				(pads allowed)
				(copperpour not_allowed)
				(footprints allowed)
			)
			(placement
				(enabled no)
				(sheetname "")
			)
			(fill
				(thermal_gap 0.5)
				(thermal_bridge_width 0.5)
				(island_removal_mode 0)
			)
			(polygon
				(pts
					(xy 107.363768 -80.0481) (xy 106.601768 -80.0481) (xy 106.601768 -80.5561) (xy 107.363768 -80.5561)
				)
			)
		)
	)
)
